FILE_TYPE = CONNECTIVITY;
{Allegro Design Entry HDL 16.6-p007 (v16-6-112F) 10/10/2012}
"PAGE_NUMBER" = 76;
0"NC";
1"GND\g";
2"GND\g";
3"GND\g";
4"GND\g";
5"PVCCIN_CPU1\g";
6"PVCCIN_CPU1\g";
7"PVCCIN_CPU1\g";
8"PVCCIN_CPU1\g";
9"PVCCIN_CPU1\g";
10"PVCCIN_CPU1\g";
11"PVCCIN_CPU1\g";
12"PVCCIN_CPU1\g";
13"PVCCIN_CPU1\g";
14"PVCCIN_CPU1\g";
15"PVCCIN_CPU1\g";
16"GND\g";
17"PVCCMCP_CPU1\g";
18"PVCCMCP_CPU1\g";
19"PVCCIO_CPU1\g";
20"GND\g";
21"PVCCMCP_CPU1\g";
22"GND\g";
23"GND\g";
24"GND\g";
25"PVCCIN_CPU1\g";
26"GND\g";
27"GND\g";
28"GND\g";
29"GND\g";
30"GND\g";
31"PVCCIN_CPU1\g";
32"GND\g";
33"PVCCMCP_CPU1\g";
34"GND\g";
35"GND\g";
36"PVSA_CPU1\g";
37"PVCCIO_CPU1\g";
38"GND\g";
39"PVSA_CPU1\g";
40"GND\g";
41"GND\g";
42"PVCCIN_CPU1\g";
43"GND\g";
44"GND\g";
%"CAP_A"
"1","(-1275,4450)","0","dev_discrete","I1";
;
VOLTAGE"4V"
LOCATION"C3D21"
PART_NUMBER"E15431-004"
MATERIAL"X6S"
PACK_TYPE"0603V"
TOLERANCE"20%"
VALUE"22.0UF"
GROUP"PWR_MCP_CAP"
ROOM"PVCCIN_CPU1_DECAP_VR"
$SEC"1"
CDS_SEC"1"
CDS_LIB"dev_discrete"
BOM_COST"PROC"
CDS_LOCATION"C3D21";
"B"
$PN"2"20;
"A"
$PN"1"17;
%"CAP_A"
"1","(-3250,4450)","0","dev_discrete","I10";
;
TOLERANCE"20%"
VALUE"22.0UF"
LOCATION"C2D40"
PACK_TYPE"0603V"
PART_NUMBER"E15431-004"
VOLTAGE"4V"
MATERIAL"X6S"
GROUP"PWR_MCP_CAP"
CDS_LOCATION"C2D40"
BOM_COST"PROC"
CDS_LIB"dev_discrete"
CDS_SEC"1"
$SEC"1"
ROOM"PVCCIN_CPU1_DECAP_VR";
"B"
$PN"2"20;
"A"
$PN"1"17;
%"CAP"
"1","(-5950,1500)","0","mstr_discrete","I103";
;
LOCATION"C8P19"
VALUE"47UF"
VOLTAGE"4V"
PART_NUMBER"C95333-006"
TOLERANCE"20%"
GROUP"PWR_MLCC_CAP"
PACK_TYPE"0805"
MATERIAL"X6S"
ROOM"PVCCIN_CPU1_DECAP_VR"
CDS_LOCATION"C8P19"
$SEC"1"
CDS_SEC"1"
BOM_COST"PROC"
CDS_LIB"mstr_discrete";
"A"
$PN"1"13;
"B"
$PN"2"29;
%"CAP"
"1","(-5950,800)","0","mstr_discrete","I107";
;
VALUE"47UF"
PACK_TYPE"0805"
MATERIAL"X6S"
TOLERANCE"20%"
VOLTAGE"4V"
LOCATION"C8P12"
GROUP"PWR_MLCC_CAP"
PART_NUMBER"C95333-006"
BOM_COST"PROC"
CDS_LIB"mstr_discrete"
CDS_SEC"1"
$SEC"1"
CDS_LOCATION"C8P12"
ROOM"PVCCIN_CPU1_DECAP_VR";
"A"
$PN"1"14;
"B"
$PN"2"23;
%"CAP_A"
"1","(-6750,3750)","0","dev_discrete","I108";
;
GROUP"PWR_MLCC_CAP"
TOLERANCE"20%"
MATERIAL"X6S"
PART_NUMBER"E15431-004"
PACK_TYPE"0603V"
VOLTAGE"4V"
VALUE"22.0UF"
LOCATION"C2D26"
ROOM"PVCCIN_CPU1_DECAP_VR"
$SEC"1"
CDS_SEC"1"
CDS_LIB"dev_discrete"
BOM_COST"PROC"
CDS_LOCATION"C2D26";
"B"
$PN"2"1;
"A"
$PN"1"6;
%"GND"
"1","(-7750,3475)","0","mstr_symbols","I109";
;
VOLTAGE"0"
CDS_LIB"mstr_symbols"
SIZE"1B"
BODY_TYPE"PLUMBING"
ROOM"PVCCIN_CPU1_DECAP_VR"
HDL_POWER"GND";
"A\NAC"1;
%"CAP_A"
"1","(-6750,3050)","0","dev_discrete","I112";
;
TOLERANCE"20%"
VALUE"22.0UF"
MATERIAL"X6S"
VOLTAGE"4V"
LOCATION"C2D23"
GROUP"PWR_MLCC_CAP"
PACK_TYPE"0603V"
PART_NUMBER"E15431-004"
ROOM"PVCCIN_CPU1_DECAP_VR"
$SEC"1"
CDS_SEC"1"
CDS_LIB"dev_discrete"
BOM_COST"PROC"
CDS_LOCATION"C2D23";
"B"
$PN"2"2;
"A"
$PN"1"7;
%"GND"
"1","(-7750,2775)","0","mstr_symbols","I113";
;
VOLTAGE"0"
CDS_LIB"mstr_symbols"
SIZE"1B"
BODY_TYPE"PLUMBING"
ROOM"PVCCIN_CPU1_DECAP_VR"
HDL_POWER"GND";
"A\NAC"2;
%"CAP_A"
"1","(-7050,3050)","0","dev_discrete","I114";
;
TOLERANCE"20%"
MATERIAL"X6S"
VALUE"22.0UF"
LOCATION"C2D17"
PART_NUMBER"E15431-004"
PACK_TYPE"0603V"
VOLTAGE"4V"
GROUP"PWR_MLCC_CAP"
ROOM"PVCCIN_CPU1_DECAP_VR"
$SEC"1"
CDS_SEC"1"
CDS_LIB"dev_discrete"
BOM_COST"PROC"
CDS_LOCATION"C2D17";
"B"
$PN"2"2;
"A"
$PN"1"7;
%"CAP"
"1","(-7150,2200)","0","mstr_discrete","I118";
;
VALUE"47UF"
VOLTAGE"4V"
LOCATION"C8P26"
MATERIAL"X6S"
PACK_TYPE"0805"
GROUP"PWR_MLCC_CAP"
PART_NUMBER"C95333-006"
TOLERANCE"20%"
CDS_LIB"mstr_discrete"
BOM_COST"PROC"
CDS_SEC"1"
$SEC"1"
CDS_LOCATION"C8P26"
ROOM"PVCCIN_CPU1_DECAP_VR";
"A"
$PN"1"11;
"B"
$PN"2"26;
%"CAP_A"
"1","(-7450,3750)","0","dev_discrete","I119";
;
GROUP"PWR_MLCC_CAP"
MATERIAL"X6S"
PACK_TYPE"0603V"
TOLERANCE"20%"
VOLTAGE"4V"
VALUE"22.0UF"
LOCATION"C2D37"
PART_NUMBER"E15431-004"
ROOM"PVCCIN_CPU1_DECAP_VR"
$SEC"1"
CDS_SEC"1"
CDS_LIB"dev_discrete"
BOM_COST"PROC"
CDS_LOCATION"C2D37";
"B"
$PN"2"1;
"A"
$PN"1"6;
%"CAP_A"
"1","(-7750,3750)","0","dev_discrete","I122";
;
MATERIAL"X6S"
PART_NUMBER"E15431-004"
GROUP"PWR_MLCC_CAP"
LOCATION"C2D34"
VALUE"22.0UF"
VOLTAGE"4V"
TOLERANCE"20%"
PACK_TYPE"0603V"
CDS_LOCATION"C2D34"
BOM_COST"PROC"
CDS_LIB"dev_discrete"
CDS_SEC"1"
$SEC"1"
ROOM"PVCCIN_CPU1_DECAP_VR";
"B"
$PN"2"1;
"A"
$PN"1"6;
%"CAP_A"
"1","(-7750,3050)","0","dev_discrete","I124";
;
PART_NUMBER"E15431-004"
TOLERANCE"20%"
VALUE"22.0UF"
LOCATION"C2D16"
VOLTAGE"4V"
MATERIAL"X6S"
PACK_TYPE"0603V"
GROUP"PWR_MLCC_CAP"
CDS_LOCATION"C2D16"
BOM_COST"PROC"
CDS_LIB"dev_discrete"
CDS_SEC"1"
$SEC"1"
ROOM"PVCCIN_CPU1_DECAP_VR";
"B"
$PN"2"2;
"A"
$PN"1"7;
%"CAP"
"1","(-7450,2200)","0","mstr_discrete","I125";
;
VOLTAGE"4V"
GROUP"PWR_MLCC_CAP"
LOCATION"C8P29"
VALUE"47UF"
PACK_TYPE"0805"
MATERIAL"X6S"
PART_NUMBER"C95333-006"
TOLERANCE"20%"
CDS_LIB"mstr_discrete"
BOM_COST"PROC"
CDS_SEC"1"
$SEC"1"
CDS_LOCATION"C8P29"
ROOM"PVCCIN_CPU1_DECAP_VR";
"A"
$PN"1"11;
"B"
$PN"2"26;
%"CAP"
"1","(-7750,2200)","0","mstr_discrete","I127";
;
VALUE"47UF"
VOLTAGE"4V"
GROUP"PWR_MLCC_CAP"
LOCATION"C8P10"
MATERIAL"X6S"
PART_NUMBER"C95333-006"
PACK_TYPE"0805"
TOLERANCE"20%"
CDS_LIB"mstr_discrete"
BOM_COST"PROC"
CDS_SEC"1"
$SEC"1"
CDS_LOCATION"C8P10"
ROOM"PVCCIN_CPU1_DECAP_VR";
"A"
$PN"1"11;
"B"
$PN"2"26;
%"CAP"
"1","(-6550,1500)","0","mstr_discrete","I129";
;
VOLTAGE"4V"
VALUE"47UF"
TOLERANCE"20%"
MATERIAL"X6S"
PACK_TYPE"0805"
LOCATION"C8P16"
PART_NUMBER"C95333-006"
GROUP"PWR_MLCC_CAP"
BOM_COST"PROC"
CDS_LIB"mstr_discrete"
CDS_SEC"1"
$SEC"1"
CDS_LOCATION"C8P16"
ROOM"PVCCIN_CPU1_DECAP_VR";
"A"
$PN"1"25;
"B"
$PN"2"3;
%"GND"
"1","(-6550,1225)","0","mstr_symbols","I130";
;
HDL_POWER"GND"
ROOM"PVCCIN_CPU1_DECAP_VR"
BODY_TYPE"PLUMBING"
CDS_LIB"mstr_symbols"
SIZE"1B"
VOLTAGE"0";
"A\NAC"3;
%"CAP"
"1","(-7150,1500)","0","mstr_discrete","I132";
;
PACK_TYPE"0805"
LOCATION"C8P13"
VALUE"47UF"
VOLTAGE"4V"
GROUP"PWR_MLCC_CAP"
MATERIAL"X6S"
PART_NUMBER"C95333-006"
TOLERANCE"20%"
BOM_COST"PROC"
CDS_LIB"mstr_discrete"
CDS_SEC"1"
$SEC"1"
CDS_LOCATION"C8P13"
ROOM"PVCCIN_CPU1_DECAP_VR";
"A"
$PN"1"12;
"B"
$PN"2"24;
%"GND"
"1","(-7750,525)","0","mstr_symbols","I134";
;
VOLTAGE"0"
CDS_LIB"mstr_symbols"
SIZE"1B"
BODY_TYPE"PLUMBING"
ROOM"PVCCIN_CPU1_DECAP_VR"
HDL_POWER"GND";
"A\NAC"4;
%"CAP"
"1","(-7450,1500)","0","mstr_discrete","I137";
;
LOCATION"C8P28"
VALUE"47UF"
VOLTAGE"4V"
MATERIAL"X6S"
GROUP"PWR_MLCC_CAP"
PACK_TYPE"0805"
PART_NUMBER"C95333-006"
TOLERANCE"20%"
ROOM"PVCCIN_CPU1_DECAP_VR"
CDS_LOCATION"C8P28"
$SEC"1"
CDS_SEC"1"
CDS_LIB"mstr_discrete"
BOM_COST"PROC";
"A"
$PN"1"12;
"B"
$PN"2"24;
%"CAP"
"1","(-7750,1500)","0","mstr_discrete","I139";
;
VOLTAGE"4V"
VALUE"47UF"
LOCATION"C8P11"
GROUP"PWR_MLCC_CAP"
PACK_TYPE"0805"
PART_NUMBER"C95333-006"
MATERIAL"X6S"
TOLERANCE"20%"
CDS_LIB"mstr_discrete"
BOM_COST"PROC"
CDS_SEC"1"
$SEC"1"
CDS_LOCATION"C8P11"
ROOM"PVCCIN_CPU1_DECAP_VR";
"A"
$PN"1"12;
"B"
$PN"2"24;
%"PVCCIN_CPU1"
"1","(-5900,4750)","0","mstr_symbols","I143";
;
HDL_POWER"PVCCIN_CPU1"
ROOM"PVCCIN_CPU1_DECAP_VR"
BODY_TYPE"PLUMBING"
CDS_LIB"mstr_symbols"
VOLTAGE"2.0V";
"G\NAC"5;
%"PVCCIN_CPU1"
"1","(-7750,4050)","0","mstr_symbols","I144";
;
HDL_POWER"PVCCIN_CPU1"
ROOM"PVCCIN_CPU1_DECAP_VR"
BODY_TYPE"PLUMBING"
CDS_LIB"mstr_symbols"
VOLTAGE"2.0V";
"G\NAC"6;
%"PVCCIN_CPU1"
"1","(-7750,3350)","0","mstr_symbols","I145";
;
HDL_POWER"PVCCIN_CPU1"
ROOM"PVCCIN_CPU1_DECAP_VR"
BODY_TYPE"PLUMBING"
CDS_LIB"mstr_symbols"
VOLTAGE"2.0V";
"G\NAC"7;
%"PVCCIN_CPU1"
"1","(-5900,4050)","0","mstr_symbols","I146";
;
VOLTAGE"2.0V"
CDS_LIB"mstr_symbols"
BODY_TYPE"PLUMBING"
ROOM"PVCCIN_CPU1_DECAP_VR"
HDL_POWER"PVCCIN_CPU1";
"G\NAC"8;
%"PVCCIN_CPU1"
"1","(-5900,3350)","0","mstr_symbols","I147";
;
VOLTAGE"2.0V"
CDS_LIB"mstr_symbols"
BODY_TYPE"PLUMBING"
ROOM"PVCCIN_CPU1_DECAP_VR"
HDL_POWER"PVCCIN_CPU1";
"G\NAC"9;
%"CAP_A"
"1","(-2350,3750)","0","dev_discrete","I15";
;
VALUE"22.0UF"
LOCATION"C3D9"
TOLERANCE"20%"
VOLTAGE"4V"
GROUP"PWR_MLCC_CAP"
PACK_TYPE"0603V"
PART_NUMBER"E15431-004"
MATERIAL"X6S"
CDS_LOCATION"C3D9"
BOM_COST"PROC"
CDS_LIB"dev_discrete"
CDS_SEC"1"
$SEC"1"
ROOM"PVCCIN_CPU1_DECAP_VR";
"B"
$PN"2"16;
"A"
$PN"1"19;
%"PVCCIN_CPU1"
"1","(-5950,2500)","0","mstr_symbols","I153";
;
VOLTAGE"2.0V"
CDS_LIB"mstr_symbols"
BODY_TYPE"PLUMBING"
ROOM"PVCCIN_CPU1_DECAP_VR"
HDL_POWER"PVCCIN_CPU1";
"G\NAC"10;
%"PVCCIN_CPU1"
"1","(-7750,2500)","0","mstr_symbols","I154";
;
VOLTAGE"2.0V"
CDS_LIB"mstr_symbols"
BODY_TYPE"PLUMBING"
ROOM"PVCCIN_CPU1_DECAP_VR"
HDL_POWER"PVCCIN_CPU1";
"G\NAC"11;
%"PVCCIN_CPU1"
"1","(-7750,1800)","0","mstr_symbols","I155";
;
HDL_POWER"PVCCIN_CPU1"
ROOM"PVCCIN_CPU1_DECAP_VR"
BODY_TYPE"PLUMBING"
CDS_LIB"mstr_symbols"
VOLTAGE"2.0V";
"G\NAC"12;
%"PVCCIN_CPU1"
"1","(-5950,1800)","0","mstr_symbols","I156";
;
HDL_POWER"PVCCIN_CPU1"
ROOM"PVCCIN_CPU1_DECAP_VR"
BODY_TYPE"PLUMBING"
CDS_LIB"mstr_symbols"
VOLTAGE"2.0V";
"G\NAC"13;
%"PVCCIN_CPU1"
"1","(-5950,1100)","0","mstr_symbols","I157";
;
VOLTAGE"2.0V"
CDS_LIB"mstr_symbols"
BODY_TYPE"PLUMBING"
ROOM"PVCCIN_CPU1_DECAP_VR"
HDL_POWER"PVCCIN_CPU1";
"G\NAC"14;
%"PVCCIN_CPU1"
"1","(-7750,1100)","0","mstr_symbols","I158";
;
VOLTAGE"2.0V"
CDS_LIB"mstr_symbols"
BODY_TYPE"PLUMBING"
ROOM"PVCCIN_CPU1_DECAP_VR"
HDL_POWER"PVCCIN_CPU1";
"G\NAC"15;
%"CAP_A"
"1","(-4500,4450)","0","dev_discrete","I159";
;
TOLERANCE"20%"
PART_NUMBER"E15431-004"
GROUP"PWR_MLCC_CAP"
VALUE"22.0UF"
PACK_TYPE"0603V"
MATERIAL"X6S"
VOLTAGE"4V"
LOCATION"C2D15"
ROOM"PVCCIN_CPU1_DECAP_VR"
$SEC"1"
CDS_SEC"1"
CDS_LIB"dev_discrete"
BOM_COST"PROC"
CDS_LOCATION"C2D15";
"B"
$PN"2"40;
"A"
$PN"1"5;
%"GND"
"1","(-3850,3475)","0","mstr_symbols","I16";
;
HDL_POWER"GND"
ROOM"PVCCIN_CPU1_DECAP_VR"
BODY_TYPE"PLUMBING"
SIZE"1B"
CDS_LIB"mstr_symbols"
VOLTAGE"0";
"A\NAC"16;
%"CAP_A"
"1","(-4400,3750)","0","dev_discrete","I160";
;
PART_NUMBER"E15431-004"
LOCATION"C2D38"
VALUE"22.0UF"
PACK_TYPE"0603V"
TOLERANCE"20%"
MATERIAL"X6S"
VOLTAGE"4V"
GROUP"PWR_MLCC_CAP"
ROOM"PVCCIN_CPU1_DECAP_VR"
$SEC"1"
CDS_SEC"1"
CDS_LIB"dev_discrete"
BOM_COST"PROC"
CDS_LOCATION"C2D38";
"B"
$PN"2"43;
"A"
$PN"1"8;
%"CAP_A"
"1","(-4500,3050)","0","dev_discrete","I161";
;
VALUE"22.0UF"
VOLTAGE"4V"
MATERIAL"X6S"
PACK_TYPE"0603V"
PART_NUMBER"E15431-004"
TOLERANCE"20%"
LOCATION"C2D35"
GROUP"PWR_MLCC_CAP"
CDS_LOCATION"C2D35"
BOM_COST"PROC"
CDS_LIB"dev_discrete"
CDS_SEC"1"
$SEC"1"
ROOM"PVCCIN_CPU1_DECAP_VR";
"B"
$PN"2"44;
"A"
$PN"1"9;
%"VCC_CORE"
"1","(-4000,4725)","0","mstr_symbols","I162";
;
HDL_POWER"PVCCMCP_CPU1"
CDS_LIB"mstr_symbols";
"A"17;
%"VCC_CORE"
"1","(-4600,2475)","0","mstr_symbols","I163";
;
HDL_POWER"PVCCMCP_CPU1"
CDS_LIB"mstr_symbols";
"A"18;
%"CAP_A"
"1","(-4000,4450)","0","dev_discrete","I164";
;
PART_NUMBER"E15431-004"
TOLERANCE"20%"
MATERIAL"X6S"
VOLTAGE"4V"
VALUE"22.0UF"
PACK_TYPE"0603V"
LOCATION"C3D7"
GROUP"PWR_MCP_CAP"
ROOM"PVCCIN_CPU1_DECAP_VR"
$SEC"1"
CDS_SEC"1"
CDS_LIB"dev_discrete"
CDS_LOCATION"C3D7";
"B"
$PN"2"20;
"A"
$PN"1"17;
%"CAP_A"
"1","(-3750,4450)","0","dev_discrete","I165";
;
TOLERANCE"20%"
MATERIAL"X6S"
VOLTAGE"4V"
VALUE"22.0UF"
LOCATION"C2D39"
PACK_TYPE"0603V"
PART_NUMBER"E15431-004"
GROUP"PWR_MCP_CAP"
ROOM"PVCCIN_CPU1_DECAP_VR"
$SEC"1"
CDS_SEC"1"
CDS_LIB"dev_discrete"
BOM_COST"PROC"
CDS_LOCATION"C2D39";
"B"
$PN"2"20;
"A"
$PN"1"17;
%"CAP_A"
"1","(-3500,4450)","0","dev_discrete","I166";
;
TOLERANCE"20%"
MATERIAL"X6S"
VALUE"22.0UF"
PACK_TYPE"0603V"
LOCATION"C3D17"
VOLTAGE"4V"
PART_NUMBER"E15431-004"
GROUP"PWR_MCP_CAP"
ROOM"PVCCIN_CPU1_DECAP_VR"
$SEC"1"
CDS_SEC"1"
CDS_LIB"dev_discrete"
BOM_COST"PROC"
CDS_LOCATION"C3D17";
"B"
$PN"2"20;
"A"
$PN"1"17;
%"PVCCIO_CPU1"
"1","(-3850,4050)","0","mstr_symbols","I167";
;
VOLTAGE"1.1V"
CDS_LIB"mstr_symbols"
BODY_TYPE"PLUMBING"
HDL_POWER"PVCCIO_CPU1";
"G\NAC"19;
%"CAP_A"
"1","(-975,4450)","0","dev_discrete","I169";
;
GROUP"PWR_MCP_CAP"
TOLERANCE"20%"
VOLTAGE"4V"
PACK_TYPE"0603V"
PART_NUMBER"E15431-004"
MATERIAL"X6S"
VALUE"22.0UF"
LOCATION"C3D18"
ROOM"PVCCIN_CPU1_DECAP_VR"
$SEC"1"
CDS_SEC"1"
CDS_LIB"dev_discrete"
BOM_COST"PROC"
CDS_LOCATION"C3D18";
"B"
$PN"2"20;
"A"
$PN"1"17;
%"CAP_A"
"1","(-725,4450)","0","dev_discrete","I170";
;
GROUP"PWR_MCP_CAP"
PACK_TYPE"0603V"
PART_NUMBER"E15431-004"
MATERIAL"X6S"
TOLERANCE"20%"
VOLTAGE"4V"
VALUE"22.0UF"
LOCATION"C3D6"
ROOM"PVCCIN_CPU1_DECAP_VR"
$SEC"1"
CDS_SEC"1"
CDS_LIB"dev_discrete"
BOM_COST"PROC"
CDS_LOCATION"C3D6";
"B"
$PN"2"20;
"A"
$PN"1"17;
%"CAP_A"
"1","(-2725,4450)","0","dev_discrete","I171";
;
MATERIAL"X6S"
TOLERANCE"20%"
VOLTAGE"4V"
LOCATION"C3D14"
VALUE"22.0UF"
PACK_TYPE"0603V"
PART_NUMBER"E15431-004"
GROUP"PWR_MCP_CAP"
ROOM"PVCCIN_CPU1_DECAP_VR"
$SEC"1"
CDS_SEC"1"
CDS_LIB"dev_discrete"
BOM_COST"PROC"
CDS_LOCATION"C3D14";
"B"
$PN"2"20;
"A"
$PN"1"17;
%"CAP_A"
"1","(-3850,3750)","0","dev_discrete","I172";
;
VALUE"22.0UF"
VOLTAGE"4V"
TOLERANCE"20%"
PACK_TYPE"0603V"
PART_NUMBER"E15431-004"
MATERIAL"X6S"
LOCATION"C3D23"
GROUP"PWR_MLCC_CAP"
CDS_LOCATION"C3D23"
BOM_COST"PROC"
CDS_LIB"dev_discrete"
CDS_SEC"1"
$SEC"1"
ROOM"PVCCIN_CPU1_DECAP_VR";
"B"
$PN"2"16;
"A"
$PN"1"19;
%"CAP_A"
"1","(-3550,3750)","0","dev_discrete","I174";
;
PART_NUMBER"E15431-004"
PACK_TYPE"0603V"
MATERIAL"X6S"
VOLTAGE"4V"
TOLERANCE"20%"
GROUP"PWR_MLCC_CAP"
VALUE"22.0UF"
LOCATION"C3D15"
ROOM"PVCCIN_CPU1_DECAP_VR"
$SEC"1"
CDS_SEC"1"
CDS_LIB"dev_discrete"
BOM_COST"PROC"
CDS_LOCATION"C3D15";
"B"
$PN"2"16;
"A"
$PN"1"19;
%"CAP_A"
"1","(-3250,3750)","0","dev_discrete","I175";
;
PART_NUMBER"E15431-004"
PACK_TYPE"0603V"
MATERIAL"X6S"
GROUP"PWR_MLCC_CAP"
TOLERANCE"20%"
LOCATION"C3D24"
VALUE"22.0UF"
VOLTAGE"4V"
CDS_LOCATION"C3D24"
BOM_COST"PROC"
CDS_LIB"dev_discrete"
CDS_SEC"1"
$SEC"1"
ROOM"PVCCIN_CPU1_DECAP_VR";
"B"
$PN"2"16;
"A"
$PN"1"19;
%"CAP_A"
"1","(-2950,3750)","0","dev_discrete","I176";
;
PACK_TYPE"0603V"
MATERIAL"X6S"
PART_NUMBER"E15431-004"
LOCATION"C3D16"
VALUE"22.0UF"
GROUP"PWR_MLCC_CAP"
TOLERANCE"20%"
VOLTAGE"4V"
CDS_LOCATION"C3D16"
BOM_COST"PROC"
CDS_LIB"dev_discrete"
CDS_SEC"1"
$SEC"1"
ROOM"PVCCIN_CPU1_DECAP_VR";
"B"
$PN"2"16;
"A"
$PN"1"19;
%"CAP_A"
"1","(-2400,1150)","0","dev_discrete","I179";
;
LOCATION"C7P12"
VALUE"22.0UF"
VOLTAGE"4V"
TOLERANCE"20%"
MATERIAL"X6S"
PART_NUMBER"E15431-004"
PACK_TYPE"0603V"
GROUP"PWR_MLCC_CAP"
ROOM"PVCCIN_CPU1_DECAP_VR"
$SEC"1"
CDS_SEC"1"
CDS_LIB"dev_discrete"
BOM_COST"PROC"
CDS_LOCATION"C7P12";
"B"
$PN"2"34;
"A"
$PN"1"37;
%"CAP_A"
"1","(-2650,3750)","0","dev_discrete","I18";
;
PART_NUMBER"E15431-004"
PACK_TYPE"0603V"
VALUE"22.0UF"
LOCATION"C3D8"
MATERIAL"X6S"
GROUP"PWR_MLCC_CAP"
TOLERANCE"20%"
VOLTAGE"4V"
CDS_LOCATION"C3D8"
BOM_COST"PROC"
CDS_LIB"dev_discrete"
CDS_SEC"1"
$SEC"1"
ROOM"PVCCIN_CPU1_DECAP_VR";
"B"
$PN"2"16;
"A"
$PN"1"19;
%"CAP_A"
"1","(-1975,3775)","0","dev_discrete","I196";
;
TOLERANCE"20%"
LOCATION"C3D10"
GROUP"PWR_MCP_CAP"
MATERIAL"X6S"
VOLTAGE"4V"
VALUE"22.0UF"
PART_NUMBER"E15431-004"
PACK_TYPE"0603V"
CDS_LOCATION"C3D10"
BOM_COST"PROC"
CDS_LIB"dev_discrete"
CDS_SEC"1"
$SEC"1"
ROOM"PVCCIN_CPU1_DECAP_VR";
"B"
$PN"2"22;
"A"
$PN"1"21;
%"CAP_A"
"1","(-1725,3775)","0","dev_discrete","I197";
;
TOLERANCE"20%"
VOLTAGE"4V"
VALUE"22.0UF"
GROUP"PWR_MCP_CAP"
PART_NUMBER"E15431-004"
MATERIAL"X6S"
LOCATION"C2D18"
PACK_TYPE"0603V"
CDS_LOCATION"C2D18"
BOM_COST"PROC"
CDS_LIB"dev_discrete"
CDS_SEC"1"
$SEC"1"
ROOM"PVCCIN_CPU1_DECAP_VR";
"B"
$PN"2"22;
"A"
$PN"1"21;
%"CAP_A"
"1","(-1475,3775)","0","dev_discrete","I198";
;
VOLTAGE"4V"
VALUE"22.0UF"
GROUP"PWR_MCP_CAP"
PACK_TYPE"0603V"
PART_NUMBER"E15431-004"
MATERIAL"X6S"
TOLERANCE"20%"
LOCATION"C2D28"
ROOM"PVCCIN_CPU1_DECAP_VR"
$SEC"1"
CDS_SEC"1"
CDS_LIB"dev_discrete"
BOM_COST"PROC"
CDS_LOCATION"C2D28";
"B"
$PN"2"22;
"A"
$PN"1"21;
%"CAP_A"
"1","(-1225,3775)","0","dev_discrete","I199";
;
GROUP"PWR_MCP_CAP"
VALUE"22.0UF"
VOLTAGE"4V"
LOCATION"C2D29"
MATERIAL"X6S"
TOLERANCE"20%"
PACK_TYPE"0603V"
PART_NUMBER"E15431-004"
ROOM"PVCCIN_CPU1_DECAP_VR"
$SEC"1"
CDS_SEC"1"
CDS_LIB"dev_discrete"
BOM_COST"PROC"
CDS_LOCATION"C2D29";
"B"
$PN"2"22;
"A"
$PN"1"21;
%"GND"
"1","(-725,4100)","0","mstr_symbols","I2";
;
VOLTAGE"0"
SIZE"1B"
CDS_LIB"mstr_symbols"
BODY_TYPE"PLUMBING"
ROOM"PVCCIN_CPU1_DECAP_VR"
HDL_POWER"GND";
"A\NAC"20;
%"CAP_A"
"1","(-2100,1150)","0","dev_discrete","I206";
;
GROUP"PWR_MLCC_CAP"
VOLTAGE"4V"
TOLERANCE"20%"
VALUE"22.0UF"
PACK_TYPE"0603V"
MATERIAL"X6S"
LOCATION"C7P16"
PART_NUMBER"E15431-004"
ROOM"PVCCIN_CPU1_DECAP_VR"
$SEC"1"
CDS_SEC"1"
CDS_LIB"dev_discrete"
BOM_COST"PROC"
CDS_LOCATION"C7P16";
"B"
$PN"2"34;
"A"
$PN"1"37;
%"CAP_A"
"1","(-750,3775)","0","dev_discrete","I207";
;
GROUP"PWR_MCP_CAP"
PART_NUMBER"E15431-004"
MATERIAL"X6S"
TOLERANCE"20%"
LOCATION"C3D20"
VALUE"22.0UF"
VOLTAGE"4V"
PACK_TYPE"0603V"
CDS_LOCATION"C3D20"
BOM_COST"PROC"
CDS_LIB"dev_discrete"
CDS_SEC"1"
$SEC"1"
ROOM"PVCCIN_CPU1_DECAP_VR";
"B"
$PN"2"22;
"A"
$PN"1"21;
%"CAP_A"
"1","(-975,3775)","0","dev_discrete","I208";
;
GROUP"PWR_MCP_CAP"
VOLTAGE"4V"
MATERIAL"X6S"
PART_NUMBER"E15431-004"
LOCATION"C3D19"
VALUE"22.0UF"
PACK_TYPE"0603V"
TOLERANCE"20%"
ROOM"PVCCIN_CPU1_DECAP_VR"
$SEC"1"
CDS_SEC"1"
CDS_LIB"dev_discrete"
BOM_COST"PROC"
CDS_LOCATION"C3D19";
"B"
$PN"2"22;
"A"
$PN"1"21;
%"VCC_CORE"
"1","(-1975,4025)","0","mstr_symbols","I209";
;
HDL_POWER"PVCCMCP_CPU1"
CDS_LIB"mstr_symbols";
"A"21;
%"GND"
"1","(-750,3450)","0","mstr_symbols","I210";
;
VOLTAGE"0"
CDS_LIB"mstr_symbols"
SIZE"1B"
BODY_TYPE"PLUMBING"
ROOM"PVCCIN_CPU1_DECAP_VR"
HDL_POWER"GND";
"A\NAC"22;
%"CAP"
"1","(-6850,2200)","0","mstr_discrete","I215";
;
CDS_SEC"1"
PACK_TYPE"0805"
LOCATION"C7P19"
VALUE"47UF"
VOLTAGE"4V"
MATERIAL"X6S"
PART_NUMBER"C95333-006"
TOLERANCE"20%"
GROUP"PWR_MLCC_CAP"
SEC_TYPE"0805"
SEC"1"
CDS_LIB"mstr_discrete"
BOM_COST"PROC"
CDS_LOCATION"C7P19"
ROOM"PVCCIN_CPU1_DECAP_VR";
"A"
$PN"1"11;
"B"
$PN"2"26;
%"CAP"
"1","(-7750,800)","0","mstr_discrete","I217";
;
CDS_SEC"1"
LOCATION"C8P24"
VALUE"47UF"
MATERIAL"X6S"
PART_NUMBER"C95333-006"
PACK_TYPE"0805"
GROUP"PWR_MLCC_CAP"
VOLTAGE"4V"
TOLERANCE"20%"
SEC_TYPE"0805"
SEC"1"
ROOM"PVCCIN_CPU1_DECAP_VR"
CDS_LOCATION"C8P24"
BOM_COST"PROC"
CDS_LIB"mstr_discrete";
"A"
$PN"1"15;
"B"
$PN"2"4;
%"GND"
"1","(-5950,525)","0","mstr_symbols","I224";
;
VOLTAGE"0"
SIZE"1B"
CDS_LIB"mstr_symbols"
BODY_TYPE"PLUMBING"
ROOM"PVCCIN_CPU1_DECAP_VR"
HDL_POWER"GND";
"A\NAC"23;
%"GND"
"1","(-7750,1225)","0","mstr_symbols","I228";
;
HDL_POWER"GND"
ROOM"PVCCIN_CPU1_DECAP_VR"
BODY_TYPE"PLUMBING"
CDS_LIB"mstr_symbols"
SIZE"1B"
VOLTAGE"0";
"A\NAC"24;
%"PVCCIN_CPU1"
"1","(-6550,1800)","0","mstr_symbols","I229";
;
VOLTAGE"2.0V"
CDS_LIB"mstr_symbols"
BODY_TYPE"PLUMBING"
ROOM"PVCCIN_CPU1_DECAP_VR"
HDL_POWER"PVCCIN_CPU1";
"G\NAC"25;
%"GND"
"1","(-7750,1925)","0","mstr_symbols","I231";
;
VOLTAGE"0"
SIZE"1B"
CDS_LIB"mstr_symbols"
BODY_TYPE"PLUMBING"
ROOM"PVCCIN_CPU1_DECAP_VR"
HDL_POWER"GND";
"A\NAC"26;
%"GND"
"1","(-5950,1925)","0","mstr_symbols","I233";
;
HDL_POWER"GND"
ROOM"PVCCIN_CPU1_DECAP_VR"
BODY_TYPE"PLUMBING"
CDS_LIB"mstr_symbols"
SIZE"1B"
VOLTAGE"0";
"A\NAC"27;
%"GND"
"1","(-4600,1975)","0","mstr_symbols","I24";
;
VOLTAGE"0"
CDS_LIB"mstr_symbols"
SIZE"1B"
BODY_TYPE"PLUMBING"
ROOM"PVCCIN_CPU1_DECAP_VR"
HDL_POWER"GND";
"A\NAC"28;
%"GND"
"1","(-5950,1225)","0","mstr_symbols","I240";
;
HDL_POWER"GND"
ROOM"PVCCIN_CPU1_DECAP_VR"
BODY_TYPE"PLUMBING"
SIZE"1B"
CDS_LIB"mstr_symbols"
VOLTAGE"0";
"A\NAC"29;
%"GND"
"1","(-1200,1050)","0","mstr_symbols","I241";
;
VOLTAGE"0"
CDS_LIB"mstr_symbols"
SIZE"1B"
BODY_TYPE"PLUMBING"
HDL_POWER"GND";
"A\NAC"30;
%"PVCCIN_CPU1"
"1","(-1200,1550)","0","mstr_symbols","I244";
;
VOLTAGE"2.0V"
CDS_LIB"mstr_symbols"
BODY_TYPE"PLUMBING"
ROOM"PVCCIN_CPU1_DECAP_VR"
HDL_POWER"PVCCIN_CPU1";
"G\NAC"31;
%"CAP"
"1","(-1200,1300)","0","mstr_discrete","I245";
;
NEW_PN"078.1071T.M002"
NEW_MATERIAL"X6S"
GROUP"PWR_MLCC_CAP"
PACK_TYPE"0805"
PART_NUMBER"602433-112"
VALUE"100UF"
LOCATION"C8W4"
VOLTAGE"4V"
TOLERANCE"20%"
CDS_SEC"1"
CDS_LIB"mstr_discrete"
BOM_COST"MEM_VRD_PVDDQ_CD"
ROOM"VDDQ_ABC_PWR_VR"
SEC_TYPE"0805"
SEC"1"
MATERIAL"X5R"
CDS_LOCATION"C8W4";
"A"
$PN"1"31;
"B"
$PN"2"30;
%"CAP"
"1","(-4550,1150)","0","mstr_discrete","I246";
;
GROUP"PWR_MLCC_CAP"
VOLTAGE"4V"
VALUE"22UF"
PART_NUMBER"C95333-002"
LOCATION"C8P5"
TOLERANCE"20%"
PACK_TYPE"0805LF"
MATERIAL"X6S"
CDS_LIB"mstr_discrete"
BOM_COST"PROC_SOCKET"
CDS_SEC"1"
$SEC"1"
ROOM"PVCCIN_CPU0_DECAP_VR"
CDS_LOCATION"C8P5";
"A"
$PN"1"39;
"B"
$PN"2"38;
%"CAP"
"1","(-4250,1150)","0","mstr_discrete","I247";
;
PART_NUMBER"C95333-002"
TOLERANCE"20%"
MATERIAL"X6S"
VOLTAGE"4V"
VALUE"22UF"
LOCATION"C8P6"
PACK_TYPE"0805LF"
GROUP"PWR_MLCC_CAP"
CDS_LIB"mstr_discrete"
BOM_COST"PROC_SOCKET"
CDS_SEC"1"
$SEC"1"
ROOM"PVCCIN_CPU0_DECAP_VR"
CDS_LOCATION"C8P6";
"A"
$PN"1"39;
"B"
$PN"2"38;
%"CAP"
"1","(-3950,1150)","0","mstr_discrete","I248";
;
LOCATION"C8P7"
VALUE"22UF"
TOLERANCE"20%"
PART_NUMBER"C95333-002"
PACK_TYPE"0805LF"
VOLTAGE"4V"
MATERIAL"X6S"
GROUP"PWR_MLCC_CAP"
ROOM"PVCCIN_CPU0_DECAP_VR"
$SEC"1"
CDS_SEC"1"
BOM_COST"PROC_SOCKET"
CDS_LIB"mstr_discrete"
CDS_LOCATION"C8P7";
"A"
$PN"1"39;
"B"
$PN"2"38;
%"CAP"
"1","(-6850,800)","0","mstr_discrete","I249";
;
CDS_SEC"1"
VOLTAGE"4V"
PACK_TYPE"0805"
VALUE"47UF"
MATERIAL"X6S"
GROUP"PWR_MLCC_CAP"
LOCATION"C8P21"
PART_NUMBER"C95333-006"
TOLERANCE"20%"
CDS_LIB"mstr_discrete"
BOM_COST"PROC"
ROOM"PVCCIN_CPU1_DECAP_VR"
SEC"1"
SEC_TYPE"0805"
CDS_LOCATION"C8P21";
"A"
$PN"1"15;
"B"
$PN"2"4;
%"CAP"
"1","(-7450,800)","0","mstr_discrete","I250";
;
CDS_SEC"1"
VALUE"47UF"
VOLTAGE"4V"
LOCATION"C8P27"
MATERIAL"X6S"
GROUP"PWR_MLCC_CAP"
PACK_TYPE"0805"
PART_NUMBER"C95333-006"
TOLERANCE"20%"
SEC_TYPE"0805"
SEC"1"
ROOM"PVCCIN_CPU1_DECAP_VR"
BOM_COST"PROC"
CDS_LIB"mstr_discrete"
CDS_LOCATION"C8P27";
"A"
$PN"1"15;
"B"
$PN"2"4;
%"CAP"
"1","(-7150,800)","0","mstr_discrete","I251";
;
CDS_SEC"1"
LOCATION"C8P25"
PACK_TYPE"0805"
VALUE"47UF"
VOLTAGE"4V"
MATERIAL"X6S"
GROUP"PWR_MLCC_CAP"
PART_NUMBER"C95333-006"
TOLERANCE"20%"
SEC_TYPE"0805"
SEC"1"
ROOM"PVCCIN_CPU1_DECAP_VR"
BOM_COST"PROC"
CDS_LIB"mstr_discrete"
CDS_LOCATION"C8P25";
"A"
$PN"1"15;
"B"
$PN"2"4;
%"CAP"
"1","(-6550,800)","0","mstr_discrete","I252";
;
CDS_SEC"1"
LOCATION"C8P17"
VALUE"47UF"
VOLTAGE"4V"
PACK_TYPE"0805"
MATERIAL"X6S"
GROUP"PWR_MLCC_CAP"
PART_NUMBER"C95333-006"
TOLERANCE"20%"
CDS_LIB"mstr_discrete"
BOM_COST"PROC"
ROOM"PVCCIN_CPU1_DECAP_VR"
SEC"1"
SEC_TYPE"0805"
CDS_LOCATION"C8P17";
"A"
$PN"1"15;
"B"
$PN"2"4;
%"GND"
"1","(-1100,2775)","0","mstr_symbols","I253";
;
HDL_POWER"GND"
BODY_TYPE"PLUMBING"
CDS_LIB"mstr_symbols"
SIZE"1B"
VOLTAGE"0";
"A\NAC"32;
%"CAP_A"
"1","(-1100,3050)","0","dev_discrete","I254";
;
CDS_SEC"1"
LOCATION"C3W4"
MATERIAL"X6S"
PART_NUMBER"E15431-004"
VOLTAGE"4V"
TOLERANCE"20%"
VALUE"22.0UF"
PACK_TYPE"0603V"
GROUP"PWR_MCP_CAP"
CDS_LOCATION"C3W4"
SEC_TYPE"0603V"
SEC"1"
BOM_COST"PROC_SOCKET"
CDS_LIB"dev_discrete"
ROOM"PVCCIN_CPU0_DECAP_VR";
"B"
$PN"2"32;
"A"
$PN"1"33;
%"CAP_A"
"1","(-1400,3050)","0","dev_discrete","I256";
;
CDS_SEC"1"
VALUE"22.0UF"
GROUP"PWR_MCP_CAP"
PART_NUMBER"E15431-004"
PACK_TYPE"0603V"
MATERIAL"X6S"
TOLERANCE"20%"
VOLTAGE"4V"
LOCATION"C3W3"
CDS_LOCATION"C3W3"
SEC_TYPE"0603V"
SEC"1"
BOM_COST"PROC_SOCKET"
CDS_LIB"dev_discrete"
ROOM"PVCCIN_CPU0_DECAP_VR";
"B"
$PN"2"32;
"A"
$PN"1"33;
%"VCC_CORE"
"1","(-1400,3325)","0","mstr_symbols","I257";
;
HDL_POWER"PVCCMCP_CPU1"
CDS_LIB"mstr_symbols";
"A"33;
%"CAP"
"1","(-4600,2200)","0","mstr_discrete","I258";
;
NEW_MATERIAL"X6S"
NEW_PN"078.1071T.M002"
PACK_TYPE"0805"
LOCATION"C7P9"
VOLTAGE"4V"
TOLERANCE"20%"
VALUE"100UF"
PART_NUMBER"602433-112"
GROUP"PWR_MCP_CAP"
CDS_LOCATION"C7P9"
MATERIAL"X5R"
SEC"1"
SEC_TYPE"0805"
ROOM"VDDQ_ABC_PWR_VR"
BOM_COST"MEM_VRD_PVDDQ_CD"
CDS_LIB"mstr_discrete"
CDS_SEC"1";
"A"
$PN"1"18;
"B"
$PN"2"28;
%"CAP"
"1","(-4350,2200)","0","mstr_discrete","I259";
;
PART_NUMBER"602433-112"
TOLERANCE"20%"
VOLTAGE"4V"
VALUE"100UF"
PACK_TYPE"0805"
NEW_MATERIAL"X6S"
NEW_PN"078.1071T.M002"
LOCATION"C7P5"
GROUP"PWR_MCP_CAP"
CDS_LOCATION"C7P5"
MATERIAL"X5R"
SEC"1"
SEC_TYPE"0805"
ROOM"VDDQ_ABC_PWR_VR"
BOM_COST"MEM_VRD_PVDDQ_CD"
CDS_LIB"mstr_discrete"
CDS_SEC"1";
"A"
$PN"1"18;
"B"
$PN"2"28;
%"CAP"
"1","(-3850,2200)","0","mstr_discrete","I260";
;
PART_NUMBER"602433-112"
LOCATION"C8P23"
PACK_TYPE"0805"
NEW_PN"078.1071T.M002"
NEW_MATERIAL"X6S"
TOLERANCE"20%"
VOLTAGE"4V"
VALUE"100UF"
GROUP"PWR_MCP_CAP"
MATERIAL"X5R"
SEC"1"
SEC_TYPE"0805"
ROOM"VDDQ_ABC_PWR_VR"
BOM_COST"MEM_VRD_PVDDQ_CD"
CDS_LIB"mstr_discrete"
CDS_SEC"1"
CDS_LOCATION"C8P23";
"A"
$PN"1"18;
"B"
$PN"2"28;
%"CAP"
"1","(-4100,2200)","0","mstr_discrete","I261";
;
PART_NUMBER"602433-112"
LOCATION"C7P14"
VOLTAGE"4V"
VALUE"100UF"
PACK_TYPE"0805"
NEW_PN"078.1071T.M002"
NEW_MATERIAL"X6S"
TOLERANCE"20%"
GROUP"PWR_MCP_CAP"
MATERIAL"X5R"
SEC"1"
SEC_TYPE"0805"
ROOM"VDDQ_ABC_PWR_VR"
BOM_COST"MEM_VRD_PVDDQ_CD"
CDS_LIB"mstr_discrete"
CDS_SEC"1"
CDS_LOCATION"C7P14";
"A"
$PN"1"18;
"B"
$PN"2"28;
%"CAP"
"1","(-3350,2200)","0","mstr_discrete","I262";
;
PART_NUMBER"602433-112"
TOLERANCE"20%"
PACK_TYPE"0805"
NEW_PN"078.1071T.M002"
NEW_MATERIAL"X6S"
VALUE"100UF"
LOCATION"C7P11"
VOLTAGE"4V"
GROUP"PWR_MCP_CAP"
CDS_SEC"1"
CDS_LIB"mstr_discrete"
BOM_COST"MEM_VRD_PVDDQ_CD"
ROOM"VDDQ_ABC_PWR_VR"
SEC_TYPE"0805"
SEC"1"
MATERIAL"X5R"
CDS_LOCATION"C7P11";
"A"
$PN"1"18;
"B"
$PN"2"28;
%"CAP"
"1","(-3600,2200)","0","mstr_discrete","I263";
;
PART_NUMBER"602433-112"
LOCATION"C7P15"
VALUE"100UF"
PACK_TYPE"0805"
NEW_PN"078.1071T.M002"
NEW_MATERIAL"X6S"
TOLERANCE"20%"
VOLTAGE"4V"
GROUP"PWR_MCP_CAP"
CDS_SEC"1"
CDS_LIB"mstr_discrete"
BOM_COST"MEM_VRD_PVDDQ_CD"
ROOM"VDDQ_ABC_PWR_VR"
SEC_TYPE"0805"
SEC"1"
MATERIAL"X5R"
CDS_LOCATION"C7P15";
"A"
$PN"1"18;
"B"
$PN"2"28;
%"CAP"
"1","(-2850,2200)","0","mstr_discrete","I264";
;
NEW_PN"078.1071T.M002"
PART_NUMBER"602433-112"
LOCATION"C8P22"
VOLTAGE"4V"
VALUE"100UF"
NEW_MATERIAL"X6S"
PACK_TYPE"0805"
TOLERANCE"20%"
GROUP"PWR_MCP_CAP"
MATERIAL"X5R"
SEC"1"
SEC_TYPE"0805"
ROOM"VDDQ_ABC_PWR_VR"
BOM_COST"MEM_VRD_PVDDQ_CD"
CDS_LIB"mstr_discrete"
CDS_SEC"1"
CDS_LOCATION"C8P22";
"A"
$PN"1"18;
"B"
$PN"2"28;
%"CAP"
"1","(-3100,2200)","0","mstr_discrete","I265";
;
NEW_PN"078.1071T.M002"
NEW_MATERIAL"X6S"
PART_NUMBER"602433-112"
VALUE"100UF"
LOCATION"C7P8"
TOLERANCE"20%"
VOLTAGE"4V"
PACK_TYPE"0805"
GROUP"PWR_MCP_CAP"
MATERIAL"X5R"
SEC"1"
SEC_TYPE"0805"
ROOM"VDDQ_ABC_PWR_VR"
BOM_COST"MEM_VRD_PVDDQ_CD"
CDS_LIB"mstr_discrete"
CDS_SEC"1"
CDS_LOCATION"C7P8";
"A"
$PN"1"18;
"B"
$PN"2"28;
%"CAP"
"1","(-2350,2200)","0","mstr_discrete","I266";
;
NEW_MATERIAL"X6S"
NEW_PN"078.1071T.M002"
PART_NUMBER"602433-112"
LOCATION"C7P10"
VALUE"100UF"
VOLTAGE"4V"
TOLERANCE"20%"
PACK_TYPE"0805"
GROUP"PWR_MCP_CAP"
CDS_SEC"1"
CDS_LIB"mstr_discrete"
BOM_COST"MEM_VRD_PVDDQ_CD"
ROOM"VDDQ_ABC_PWR_VR"
SEC_TYPE"0805"
SEC"1"
MATERIAL"X5R"
CDS_LOCATION"C7P10";
"A"
$PN"1"18;
"B"
$PN"2"28;
%"CAP"
"1","(-2600,2200)","0","mstr_discrete","I267";
;
NEW_PN"078.1071T.M002"
NEW_MATERIAL"X6S"
TOLERANCE"20%"
PART_NUMBER"602433-112"
LOCATION"C7P7"
VALUE"100UF"
VOLTAGE"4V"
PACK_TYPE"0805"
GROUP"PWR_MCP_CAP"
CDS_SEC"1"
CDS_LIB"mstr_discrete"
BOM_COST"MEM_VRD_PVDDQ_CD"
ROOM"VDDQ_ABC_PWR_VR"
SEC_TYPE"0805"
SEC"1"
MATERIAL"X5R"
CDS_LOCATION"C7P7";
"A"
$PN"1"18;
"B"
$PN"2"28;
%"CAP"
"1","(-1850,2200)","0","mstr_discrete","I268";
;
NEW_MATERIAL"X6S"
NEW_PN"078.1071T.M002"
VALUE"100UF"
VOLTAGE"4V"
TOLERANCE"20%"
LOCATION"C7P6"
PACK_TYPE"0805"
PART_NUMBER"602433-112"
GROUP"PWR_MCP_CAP"
CDS_SEC"1"
CDS_LIB"mstr_discrete"
BOM_COST"MEM_VRD_PVDDQ_CD"
ROOM"VDDQ_ABC_PWR_VR"
SEC_TYPE"0805"
SEC"1"
MATERIAL"X5R"
CDS_LOCATION"C7P6";
"A"
$PN"1"18;
"B"
$PN"2"28;
%"CAP"
"1","(-2100,2200)","0","mstr_discrete","I269";
;
NEW_MATERIAL"X6S"
NEW_PN"078.1071T.M002"
VALUE"100UF"
VOLTAGE"4V"
TOLERANCE"20%"
LOCATION"C7P13"
PACK_TYPE"0805"
PART_NUMBER"602433-112"
GROUP"PWR_MCP_CAP"
CDS_SEC"1"
CDS_LIB"mstr_discrete"
BOM_COST"MEM_VRD_PVDDQ_CD"
ROOM"VDDQ_ABC_PWR_VR"
SEC_TYPE"0805"
SEC"1"
MATERIAL"X5R"
CDS_LOCATION"C7P13";
"A"
$PN"1"18;
"B"
$PN"2"28;
%"CAP"
"1","(-1350,2200)","0","mstr_discrete","I270";
;
NEW_MATERIAL"X6S"
NEW_PN"078.1071T.M002"
PACK_TYPE"0805"
LOCATION"C8P15"
TOLERANCE"20%"
VOLTAGE"4V"
VALUE"100UF"
PART_NUMBER"602433-112"
GROUP"PWR_MCP_CAP"
MATERIAL"X5R"
SEC"1"
SEC_TYPE"0805"
ROOM"VDDQ_ABC_PWR_VR"
BOM_COST"MEM_VRD_PVDDQ_CD"
CDS_LIB"mstr_discrete"
CDS_SEC"1"
CDS_LOCATION"C8P15";
"A"
$PN"1"18;
"B"
$PN"2"28;
%"CAP"
"1","(-1600,2200)","0","mstr_discrete","I271";
;
NEW_PN"078.1071T.M002"
LOCATION"C7P4"
PACK_TYPE"0805"
TOLERANCE"20%"
PART_NUMBER"602433-112"
VOLTAGE"4V"
VALUE"100UF"
NEW_MATERIAL"X6S"
GROUP"PWR_MCP_CAP"
MATERIAL"X5R"
SEC"1"
SEC_TYPE"0805"
ROOM"VDDQ_ABC_PWR_VR"
BOM_COST"MEM_VRD_PVDDQ_CD"
CDS_LIB"mstr_discrete"
CDS_SEC"1"
CDS_LOCATION"C7P4";
"A"
$PN"1"18;
"B"
$PN"2"28;
%"CAP"
"1","(-1100,2200)","0","mstr_discrete","I272";
;
NEW_PN"078.1071T.M002"
NEW_MATERIAL"X6S"
PACK_TYPE"0805"
VOLTAGE"4V"
LOCATION"C8P14"
VALUE"100UF"
PART_NUMBER"602433-112"
TOLERANCE"20%"
GROUP"PWR_MCP_CAP"
CDS_SEC"1"
CDS_LIB"mstr_discrete"
BOM_COST"MEM_VRD_PVDDQ_CD"
ROOM"VDDQ_ABC_PWR_VR"
SEC_TYPE"0805"
SEC"1"
MATERIAL"X5R"
CDS_LOCATION"C8P14";
"A"
$PN"1"18;
"B"
$PN"2"28;
%"CAP"
"1","(-850,2200)","0","mstr_discrete","I273";
;
NEW_PN"078.1071T.M002"
PART_NUMBER"602433-112"
LOCATION"C8P9"
VOLTAGE"4V"
TOLERANCE"20%"
NEW_MATERIAL"X6S"
VALUE"100UF"
PACK_TYPE"0805"
GROUP"PWR_MCP_CAP"
CDS_SEC"1"
CDS_LIB"mstr_discrete"
BOM_COST"MEM_VRD_PVDDQ_CD"
ROOM"VDDQ_ABC_PWR_VR"
SEC_TYPE"0805"
SEC"1"
MATERIAL"X5R"
CDS_LOCATION"C8P9";
"A"
$PN"1"18;
"B"
$PN"2"28;
%"CAP"
"1","(-600,2200)","0","mstr_discrete","I274";
;
VALUE"100UF"
TOLERANCE"20%"
PACK_TYPE"0805"
NEW_PN"078.1071T.M002"
NEW_MATERIAL"X6S"
LOCATION"C8P8"
VOLTAGE"4V"
PART_NUMBER"602433-112"
GROUP"PWR_MCP_CAP"
MATERIAL"X5R"
SEC"1"
SEC_TYPE"0805"
ROOM"VDDQ_ABC_PWR_VR"
BOM_COST"MEM_VRD_PVDDQ_CD"
CDS_LIB"mstr_discrete"
CDS_SEC"1"
CDS_LOCATION"C8P8";
"A"
$PN"1"18;
"B"
$PN"2"28;
%"CAP"
"1","(-2700,1150)","0","mstr_discrete","I29";
;
LOCATION"C7P17"
GROUP"PWR_MLCC_CAP"
VOLTAGE"4V"
VALUE"47UF"
PACK_TYPE"0805"
TOLERANCE"20%"
PART_NUMBER"C95333-006"
MATERIAL"X6S"
ROOM"PVCCIN_CPU1_DECAP_VR"
CDS_LOCATION"C7P17"
$SEC"1"
CDS_SEC"1"
CDS_LIB"mstr_discrete"
BOM_COST"PROC";
"A"
$PN"1"37;
"B"
$PN"2"34;
%"CAP_A"
"1","(-1600,4450)","0","dev_discrete","I3";
;
TOLERANCE"20%"
GROUP"PWR_MCP_CAP"
PART_NUMBER"E15431-004"
VALUE"22.0UF"
MATERIAL"X6S"
VOLTAGE"4V"
PACK_TYPE"0603V"
LOCATION"C3D5"
ROOM"PVCCIN_CPU1_DECAP_VR"
$SEC"1"
CDS_SEC"1"
CDS_LIB"dev_discrete"
BOM_COST"PROC"
CDS_LOCATION"C3D5";
"B"
$PN"2"20;
"A"
$PN"1"17;
%"GND"
"1","(-3300,775)","0","mstr_symbols","I30";
;
HDL_POWER"GND"
ROOM"PVCCIN_CPU1_DECAP_VR"
BODY_TYPE"PLUMBING"
SIZE"1B"
CDS_LIB"mstr_symbols"
VOLTAGE"0";
"A\NAC"34;
%"CAP"
"1","(-3050,3100)","0","mstr_discrete","I33";
;
LOCATION"C2D8"
GROUP"PWR_MLCC_CAP"
VALUE"10UF"
VOLTAGE"4V"
PACK_TYPE"0603LF"
TOLERANCE"20%"
MATERIAL"X6S"
PART_NUMBER"E15431-001"
ROOM"PVCCIN_CPU1_DECAP_VR"
CDS_LOCATION"C2D8"
$SEC"1"
CDS_SEC"1"
CDS_LIB"mstr_discrete"
BOM_COST"PROC";
"A"
$PN"1"36;
"B"
$PN"2"35;
%"GND"
"1","(-3950,2775)","0","mstr_symbols","I36";
;
HDL_POWER"GND"
ROOM"PVCCIN_CPU1_DECAP_VR"
BODY_TYPE"PLUMBING"
CDS_LIB"mstr_symbols"
SIZE"1B"
VOLTAGE"0";
"A\NAC"35;
%"CAP"
"1","(-3350,3100)","0","mstr_discrete","I37";
;
LOCATION"C2D10"
MATERIAL"X6S"
VOLTAGE"4V"
TOLERANCE"20%"
VALUE"10UF"
PACK_TYPE"0603LF"
PART_NUMBER"E15431-001"
GROUP"PWR_MLCC_CAP"
BOM_COST"PROC"
CDS_LIB"mstr_discrete"
CDS_SEC"1"
$SEC"1"
CDS_LOCATION"C2D10"
ROOM"PVCCIN_CPU1_DECAP_VR";
"A"
$PN"1"36;
"B"
$PN"2"35;
%"CAP_A"
"1","(-1875,4450)","0","dev_discrete","I4";
;
MATERIAL"X6S"
GROUP"PWR_MCP_CAP"
LOCATION"C3D12"
VALUE"22.0UF"
VOLTAGE"4V"
PACK_TYPE"0603V"
TOLERANCE"20%"
PART_NUMBER"E15431-004"
ROOM"PVCCIN_CPU1_DECAP_VR"
$SEC"1"
CDS_SEC"1"
CDS_LIB"dev_discrete"
BOM_COST"PROC"
CDS_LOCATION"C3D12";
"B"
$PN"2"20;
"A"
$PN"1"17;
%"PVSA_CPU1"
"1","(-3950,3400)","0","mstr_symbols","I41";
;
HDL_POWER"PVSA_CPU1"
ROOM"PVCCIN_CPU1_DECAP_VR"
BODY_TYPE"PLUMBING"
CDS_LIB"mstr_symbols"
VOLTAGE"1.1V";
"G\NAC"36;
%"CAP"
"1","(-3650,3100)","0","mstr_discrete","I42";
;
LOCATION"C2D11"
PACK_TYPE"0603LF"
VOLTAGE"4V"
MATERIAL"X6S"
PART_NUMBER"E15431-001"
TOLERANCE"20%"
VALUE"10UF"
GROUP"PWR_MLCC_CAP"
ROOM"PVCCIN_CPU1_DECAP_VR"
CDS_LOCATION"C2D11"
$SEC"1"
CDS_SEC"1"
BOM_COST"PROC"
CDS_LIB"mstr_discrete";
"A"
$PN"1"36;
"B"
$PN"2"35;
%"CAP"
"1","(-3950,3100)","0","mstr_discrete","I43";
;
PART_NUMBER"E15431-001"
MATERIAL"X6S"
LOCATION"C2D9"
TOLERANCE"20%"
VOLTAGE"4V"
VALUE"10UF"
PACK_TYPE"0603LF"
GROUP"PWR_MLCC_CAP"
CDS_LIB"mstr_discrete"
BOM_COST"PROC"
CDS_SEC"1"
$SEC"1"
CDS_LOCATION"C2D9"
ROOM"PVCCIN_CPU1_DECAP_VR";
"A"
$PN"1"36;
"B"
$PN"2"35;
%"PVCCIO_CPU1"
"1","(-3300,1450)","0","mstr_symbols","I47";
;
HDL_POWER"PVCCIO_CPU1"
BODY_TYPE"PLUMBING"
CDS_LIB"mstr_symbols"
VOLTAGE"1.1V";
"G\NAC"37;
%"CAP_A"
"1","(-2175,4450)","0","dev_discrete","I5";
;
MATERIAL"X6S"
LOCATION"C3D4"
VALUE"22.0UF"
VOLTAGE"4V"
TOLERANCE"20%"
PART_NUMBER"E15431-004"
PACK_TYPE"0603V"
GROUP"PWR_MCP_CAP"
ROOM"PVCCIN_CPU1_DECAP_VR"
$SEC"1"
CDS_SEC"1"
CDS_LIB"dev_discrete"
BOM_COST"PROC"
CDS_LOCATION"C3D4";
"B"
$PN"2"20;
"A"
$PN"1"17;
%"CAP"
"1","(-3000,1150)","0","mstr_discrete","I51";
;
PART_NUMBER"C95333-006"
LOCATION"C7P18"
PACK_TYPE"0805"
MATERIAL"X6S"
TOLERANCE"20%"
VOLTAGE"4V"
VALUE"47UF"
GROUP"PWR_MLCC_CAP"
ROOM"PVCCIN_CPU1_DECAP_VR"
CDS_LOCATION"C7P18"
$SEC"1"
CDS_SEC"1"
CDS_LIB"mstr_discrete"
BOM_COST"PROC";
"A"
$PN"1"37;
"B"
$PN"2"34;
%"CAP"
"1","(-3300,1150)","0","mstr_discrete","I52";
;
LOCATION"C7P3"
VALUE"47UF"
GROUP"PWR_MLCC_CAP"
VOLTAGE"4V"
PART_NUMBER"C95333-006"
PACK_TYPE"0805"
MATERIAL"X6S"
TOLERANCE"20%"
ROOM"PVCCIN_CPU1_DECAP_VR"
CDS_LOCATION"C7P3"
$SEC"1"
CDS_SEC"1"
CDS_LIB"mstr_discrete"
BOM_COST"PROC";
"A"
$PN"1"37;
"B"
$PN"2"34;
%"GND"
"1","(-3950,775)","0","mstr_symbols","I53";
;
HDL_POWER"GND"
ROOM"PVCCIN_CPU1_DECAP_VR"
BODY_TYPE"PLUMBING"
SIZE"1B"
CDS_LIB"mstr_symbols"
VOLTAGE"0";
"A\NAC"38;
%"PVSA_CPU1"
"1","(-4550,1450)","0","mstr_symbols","I57";
;
VOLTAGE"1.1V"
CDS_LIB"mstr_symbols"
BODY_TYPE"PLUMBING"
HDL_POWER"PVSA_CPU1";
"G\NAC"39;
%"CAP_A"
"1","(-4800,4450)","0","dev_discrete","I59";
;
GROUP"PWR_MLCC_CAP"
MATERIAL"X6S"
TOLERANCE"20%"
LOCATION"C2D12"
VALUE"22.0UF"
VOLTAGE"4V"
PART_NUMBER"E15431-004"
PACK_TYPE"0603V"
CDS_LOCATION"C2D12"
BOM_COST"PROC"
CDS_LIB"dev_discrete"
CDS_SEC"1"
$SEC"1"
ROOM"PVCCIN_CPU1_DECAP_VR";
"B"
$PN"2"40;
"A"
$PN"1"5;
%"GND"
"1","(-5900,4175)","0","mstr_symbols","I60";
;
VOLTAGE"0"
CDS_LIB"mstr_symbols"
SIZE"1B"
BODY_TYPE"PLUMBING"
ROOM"PVCCIN_CPU1_DECAP_VR"
HDL_POWER"GND";
"A\NAC"40;
%"CAP_A"
"1","(-5100,4450)","0","dev_discrete","I61";
;
PART_NUMBER"E15431-004"
TOLERANCE"20%"
PACK_TYPE"0603V"
VOLTAGE"4V"
VALUE"22.0UF"
LOCATION"C2D22"
MATERIAL"X6S"
GROUP"PWR_MLCC_CAP"
CDS_LOCATION"C2D22"
BOM_COST"PROC"
CDS_LIB"dev_discrete"
CDS_SEC"1"
$SEC"1"
ROOM"PVCCIN_CPU1_DECAP_VR";
"B"
$PN"2"40;
"A"
$PN"1"5;
%"CAP_A"
"1","(-5600,4450)","0","dev_discrete","I63";
;
GROUP"PWR_MLCC_CAP"
MATERIAL"X6S"
TOLERANCE"20%"
PART_NUMBER"E15431-004"
VALUE"22.0UF"
LOCATION"C2D31"
VOLTAGE"4V"
PACK_TYPE"0603V"
ROOM"PVCCIN_CPU1_DECAP_VR"
$SEC"1"
CDS_SEC"1"
CDS_LIB"dev_discrete"
BOM_COST"PROC"
CDS_LOCATION"C2D31";
"B"
$PN"2"40;
"A"
$PN"1"5;
%"CAP_A"
"1","(-5900,4450)","0","dev_discrete","I65";
;
GROUP"PWR_MLCC_CAP"
VOLTAGE"4V"
PACK_TYPE"0603V"
LOCATION"C2D21"
VALUE"22.0UF"
TOLERANCE"20%"
MATERIAL"X6S"
PART_NUMBER"E15431-004"
ROOM"PVCCIN_CPU1_DECAP_VR"
$SEC"1"
CDS_SEC"1"
CDS_LIB"dev_discrete"
BOM_COST"PROC"
CDS_LOCATION"C2D21";
"B"
$PN"2"40;
"A"
$PN"1"5;
%"CAP_A"
"1","(-6650,4450)","0","dev_discrete","I66";
;
TOLERANCE"20%"
PART_NUMBER"E15431-004"
PACK_TYPE"0603V"
GROUP"PWR_MLCC_CAP"
MATERIAL"X6S"
LOCATION"C2D27"
VOLTAGE"4V"
VALUE"22.0UF"
CDS_LOCATION"C2D27"
BOM_COST"PROC"
CDS_LIB"dev_discrete"
CDS_SEC"1"
$SEC"1"
ROOM"PVCCIN_CPU1_DECAP_VR";
"B"
$PN"2"41;
"A"
$PN"1"42;
%"GND"
"1","(-7750,4175)","0","mstr_symbols","I67";
;
VOLTAGE"0"
CDS_LIB"mstr_symbols"
SIZE"1B"
BODY_TYPE"PLUMBING"
ROOM"PVCCIN_CPU1_DECAP_VR"
HDL_POWER"GND";
"A\NAC"41;
%"CAP_A"
"1","(-7350,4450)","0","dev_discrete","I69";
;
GROUP"PWR_MLCC_CAP"
LOCATION"C3D2"
TOLERANCE"20%"
MATERIAL"X6S"
PACK_TYPE"0603V"
PART_NUMBER"E15431-004"
VOLTAGE"4V"
VALUE"22.0UF"
ROOM"PVCCIN_CPU1_DECAP_VR"
$SEC"1"
CDS_SEC"1"
CDS_LIB"dev_discrete"
BOM_COST"PROC"
CDS_LOCATION"C3D2";
"B"
$PN"2"41;
"A"
$PN"1"42;
%"CAP_A"
"1","(-2450,4450)","0","dev_discrete","I7";
;
MATERIAL"X6S"
VALUE"22.0UF"
GROUP"PWR_MCP_CAP"
VOLTAGE"4V"
TOLERANCE"20%"
PART_NUMBER"E15431-004"
PACK_TYPE"0603V"
LOCATION"C3D11"
ROOM"PVCCIN_CPU1_DECAP_VR"
$SEC"1"
CDS_SEC"1"
CDS_LIB"dev_discrete"
BOM_COST"PROC"
CDS_LOCATION"C3D11";
"B"
$PN"2"20;
"A"
$PN"1"17;
%"CAP_A"
"1","(-7650,4450)","0","dev_discrete","I70";
;
PACK_TYPE"0603V"
GROUP"PWR_MLCC_CAP"
MATERIAL"X6S"
PART_NUMBER"E15431-004"
TOLERANCE"20%"
VOLTAGE"4V"
VALUE"22.0UF"
LOCATION"C2D36"
CDS_LOCATION"C2D36"
CDS_LIB"dev_discrete"
CDS_SEC"1"
$SEC"1"
BOM_COST"PROC"
ROOM"PVCCIN_CPU1_DECAP_VR";
"B"
$PN"2"41;
"A"
$PN"1"42;
%"PVCCIN_CPU1"
"1","(-7750,4750)","0","mstr_symbols","I71";
;
HDL_POWER"PVCCIN_CPU1"
ROOM"PVCCIN_CPU1_DECAP_VR"
BODY_TYPE"PLUMBING"
CDS_LIB"mstr_symbols"
VOLTAGE"2.0V";
"G\NAC"42;
%"CAP_A"
"1","(-4700,3750)","0","dev_discrete","I73";
;
GROUP"PWR_MLCC_CAP"
MATERIAL"X6S"
PART_NUMBER"E15431-004"
TOLERANCE"20%"
VALUE"22.0UF"
LOCATION"C2D13"
VOLTAGE"4V"
PACK_TYPE"0603V"
ROOM"PVCCIN_CPU1_DECAP_VR"
$SEC"1"
CDS_SEC"1"
CDS_LIB"dev_discrete"
BOM_COST"PROC"
CDS_LOCATION"C2D13";
"B"
$PN"2"43;
"A"
$PN"1"8;
%"GND"
"1","(-5900,3475)","0","mstr_symbols","I74";
;
VOLTAGE"0"
SIZE"1B"
CDS_LIB"mstr_symbols"
BODY_TYPE"PLUMBING"
ROOM"PVCCIN_CPU1_DECAP_VR"
HDL_POWER"GND";
"A\NAC"43;
%"CAP_A"
"1","(-5000,3750)","0","dev_discrete","I75";
;
PACK_TYPE"0603V"
GROUP"PWR_MLCC_CAP"
MATERIAL"X6S"
TOLERANCE"20%"
LOCATION"C2D19"
VALUE"22.0UF"
PART_NUMBER"E15431-004"
VOLTAGE"4V"
CDS_LOCATION"C2D19"
BOM_COST"PROC"
CDS_LIB"dev_discrete"
CDS_SEC"1"
$SEC"1"
ROOM"PVCCIN_CPU1_DECAP_VR";
"B"
$PN"2"43;
"A"
$PN"1"8;
%"CAP_A"
"1","(-4800,3050)","0","dev_discrete","I76";
;
PACK_TYPE"0603V"
GROUP"PWR_MLCC_CAP"
VALUE"22.0UF"
LOCATION"C2D14"
PART_NUMBER"E15431-004"
MATERIAL"X6S"
TOLERANCE"20%"
VOLTAGE"4V"
CDS_LOCATION"C2D14"
BOM_COST"PROC"
CDS_LIB"dev_discrete"
CDS_SEC"1"
$SEC"1"
ROOM"PVCCIN_CPU1_DECAP_VR";
"B"
$PN"2"44;
"A"
$PN"1"9;
%"GND"
"1","(-5900,2775)","0","mstr_symbols","I77";
;
HDL_POWER"GND"
ROOM"PVCCIN_CPU1_DECAP_VR"
BODY_TYPE"PLUMBING"
CDS_LIB"mstr_symbols"
SIZE"1B"
VOLTAGE"0";
"A\NAC"44;
%"CAP_A"
"1","(-5100,3050)","0","dev_discrete","I79";
;
GROUP"PWR_MLCC_CAP"
MATERIAL"X6S"
TOLERANCE"20%"
VALUE"22.0UF"
VOLTAGE"4V"
PACK_TYPE"0603V"
LOCATION"C2D20"
PART_NUMBER"E15431-004"
CDS_LOCATION"C2D20"
BOM_COST"PROC"
CDS_LIB"dev_discrete"
CDS_SEC"1"
$SEC"1"
ROOM"PVCCIN_CPU1_DECAP_VR";
"B"
$PN"2"44;
"A"
$PN"1"9;
%"CAP_A"
"1","(-2975,4450)","0","dev_discrete","I8";
;
TOLERANCE"20%"
VOLTAGE"4V"
GROUP"PWR_MCP_CAP"
MATERIAL"X6S"
PACK_TYPE"0603V"
VALUE"22.0UF"
LOCATION"C3D13"
PART_NUMBER"E15431-004"
ROOM"PVCCIN_CPU1_DECAP_VR"
$SEC"1"
CDS_SEC"1"
CDS_LIB"dev_discrete"
BOM_COST"PROC"
CDS_LOCATION"C3D13";
"B"
$PN"2"20;
"A"
$PN"1"17;
%"CAP_A"
"1","(-5400,3050)","0","dev_discrete","I80";
;
LOCATION"C2D24"
PART_NUMBER"E15431-004"
VALUE"22.0UF"
VOLTAGE"4V"
TOLERANCE"20%"
MATERIAL"X6S"
PACK_TYPE"0603V"
GROUP"PWR_MLCC_CAP"
CDS_LOCATION"C2D24"
BOM_COST"PROC"
CDS_LIB"dev_discrete"
CDS_SEC"1"
$SEC"1"
ROOM"PVCCIN_CPU1_DECAP_VR";
"B"
$PN"2"44;
"A"
$PN"1"9;
%"CAP_A"
"1","(-5300,3750)","0","dev_discrete","I82";
;
GROUP"PWR_MLCC_CAP"
VOLTAGE"4V"
VALUE"22.0UF"
LOCATION"C2D25"
PACK_TYPE"0603V"
TOLERANCE"20%"
PART_NUMBER"E15431-004"
MATERIAL"X6S"
ROOM"PVCCIN_CPU1_DECAP_VR"
$SEC"1"
CDS_SEC"1"
CDS_LIB"dev_discrete"
BOM_COST"PROC"
CDS_LOCATION"C2D25";
"B"
$PN"2"43;
"A"
$PN"1"8;
%"CAP_A"
"1","(-5600,3750)","0","dev_discrete","I83";
;
VOLTAGE"4V"
MATERIAL"X6S"
PART_NUMBER"E15431-004"
VALUE"22.0UF"
LOCATION"C2D30"
PACK_TYPE"0603V"
TOLERANCE"20%"
GROUP"PWR_MLCC_CAP"
ROOM"PVCCIN_CPU1_DECAP_VR"
$SEC"1"
CDS_SEC"1"
CDS_LIB"dev_discrete"
BOM_COST"PROC"
CDS_LOCATION"C2D30";
"B"
$PN"2"43;
"A"
$PN"1"8;
%"CAP_A"
"1","(-5900,3750)","0","dev_discrete","I85";
;
GROUP"PWR_MLCC_CAP"
VOLTAGE"4V"
TOLERANCE"20%"
PACK_TYPE"0603V"
PART_NUMBER"E15431-004"
MATERIAL"X6S"
LOCATION"C2D33"
VALUE"22.0UF"
ROOM"PVCCIN_CPU1_DECAP_VR"
$SEC"1"
CDS_SEC"1"
CDS_LIB"dev_discrete"
BOM_COST"PROC"
CDS_LOCATION"C2D33";
"B"
$PN"2"43;
"A"
$PN"1"8;
%"CAP"
"1","(-5650,2200)","0","mstr_discrete","I89";
;
GROUP"PWR_MLCC_CAP"
TOLERANCE"20%"
PART_NUMBER"C95333-006"
MATERIAL"X6S"
PACK_TYPE"0805"
VOLTAGE"4V"
VALUE"47UF"
LOCATION"C8P20"
CDS_LIB"mstr_discrete"
BOM_COST"PROC"
CDS_SEC"1"
$SEC"1"
CDS_LOCATION"C8P20"
ROOM"PVCCIN_CPU1_DECAP_VR";
"A"
$PN"1"10;
"B"
$PN"2"27;
%"CAP_A"
"1","(-5900,3050)","0","dev_discrete","I90";
;
VOLTAGE"4V"
MATERIAL"X6S"
PACK_TYPE"0603V"
PART_NUMBER"E15431-004"
VALUE"22.0UF"
LOCATION"C2D32"
GROUP"PWR_MLCC_CAP"
TOLERANCE"20%"
ROOM"PVCCIN_CPU1_DECAP_VR"
$SEC"1"
CDS_SEC"1"
CDS_LIB"dev_discrete"
BOM_COST"PROC"
CDS_LOCATION"C2D32";
"B"
$PN"2"44;
"A"
$PN"1"9;
%"CAP"
"1","(-5950,2200)","0","mstr_discrete","I92";
;
VOLTAGE"4V"
VALUE"47UF"
PACK_TYPE"0805"
LOCATION"C8P18"
MATERIAL"X6S"
TOLERANCE"20%"
GROUP"PWR_MLCC_CAP"
PART_NUMBER"C95333-006"
BOM_COST"PROC"
CDS_LIB"mstr_discrete"
CDS_SEC"1"
$SEC"1"
CDS_LOCATION"C8P18"
ROOM"PVCCIN_CPU1_DECAP_VR";
"A"
$PN"1"10;
"B"
$PN"2"27;
END.
